(kicad_pcb
	(version 20260206)
	(generator "pcbnew")
	(generator_version "10.0")
	(general
		(thickness 1.6)
		(legacy_teardrops no)
	)
	(paper "A4")
	(title_block
		(title "v1-chassis-manager — T6M_CM_d_v01_1031_1645.brd")
		(comment 1 "Open CloudServer (Microsoft) / footprints 92-101 of 2512")
	)
	(layers
		(0 "F.Cu" signal "TOP")
		(4 "In1.Cu" signal "GND1")
		(6 "In2.Cu" signal "IN1")
		(8 "In3.Cu" signal "VCC1")
		(10 "In4.Cu" signal "VCC2")
		(12 "In5.Cu" signal "GND2")
		(14 "In6.Cu" signal "IN2")
		(16 "In7.Cu" signal "IN3")
		(18 "In8.Cu" signal "GND3")
		(2 "B.Cu" signal "BOTTOM")
		(9 "F.Adhes" user "F.Adhesive")
		(11 "B.Adhes" user "B.Adhesive")
		(13 "F.Paste" user "Package Geometry/Pastemask Top")
		(15 "B.Paste" user "Package Geometry/Pastemask Bottom")
		(5 "F.SilkS" user "Ref Des/Silkscreen Top")
		(7 "B.SilkS" user "Ref Des/Silkscreen Bottom")
		(1 "F.Mask" user "Board Geometry/Soldermask Top")
		(3 "B.Mask" user "Board Geometry/Soldermask Bottom")
		(17 "Dwgs.User" user "User.Drawings")
		(19 "Cmts.User" user "User.Comments")
		(21 "Eco1.User" user "User.Eco1")
		(23 "Eco2.User" user "User.Eco2")
		(25 "Edge.Cuts" user "Board Geometry/Outline")
		(27 "Margin" user)
		(31 "F.CrtYd" user "Package Geometry/Place Bound Top")
		(29 "B.CrtYd" user "Package Geometry/Place Bound Bottom")
		(35 "F.Fab" user "Ref Des/Assembly Top")
		(33 "B.Fab" user "Ref Des/Assembly Bottom")
	)
	(footprint ""
		(layer "F.Cu")
		(at 55.10276 -188.126624 90)
		(property "Reference" "C589"
			(at 4.548886 0.349758 90)
			(unlocked yes)
			(layer "F.SilkS")
			(effects
				(font
					(size 0.7874 0.5842)
					(thickness 0.1524)
				)
				(justify left)
			)
		)
		(property "Value" ""
			(at 0 0 90)
			(layer "F.Fab")
			(effects
				(font
					(size 1.27 1.27)
				)
			)
		)
		(duplicate_pad_numbers_are_jumpers no)
		(fp_line
			(start 0.7874 -0.4064)
			(end 0.7874 0.4064)
			(stroke
				(width 0.1524)
				(type default)
			)
			(layer "F.SilkS")
		)
		(fp_line
			(start -0.7874 -0.4064)
			(end 0.7874 -0.4064)
			(stroke
				(width 0.1524)
				(type default)
			)
			(layer "F.SilkS")
		)
		(fp_line
			(start 0 0.381)
			(end 0 -0.381)
			(stroke
				(width 0.1524)
				(type default)
			)
			(layer "F.SilkS")
		)
		(fp_line
			(start 0.7874 0.4064)
			(end -0.7874 0.4064)
			(stroke
				(width 0.1524)
				(type default)
			)
			(layer "F.SilkS")
		)
		(fp_line
			(start -0.7874 0.4064)
			(end -0.7874 -0.4064)
			(stroke
				(width 0.1524)
				(type default)
			)
			(layer "F.SilkS")
		)
		(fp_poly
			(pts
				(xy -0.5334 0.254) (xy -0.635 0.254) (xy -0.635 0.2286) (xy -0.635 -0.254) (xy -0.5334 -0.254) (xy -0.5334 -0.2794)
				(xy 0.5334 -0.2794) (xy 0.5334 -0.254) (xy 0.635 -0.254) (xy 0.635 0.254) (xy 0.5334 0.254) (xy 0.5334 0.2794)
				(xy -0.508 0.2794) (xy -0.5334 0.2794)
			)
			(stroke
				(width 0)
				(type default)
			)
			(fill no)
			(layer "F.CrtYd")
		)
		(pad "1" smd rect
			(at 0.40005 0 90)
			(size 0.4572 0.508)
			(layers "F.Cu" "F.Mask" "F.Paste")
			(net "I2C_PSU1_R_SCL")
		)
		(pad "2" smd rect
			(at -0.40005 0 90)
			(size 0.4572 0.508)
			(layers "F.Cu" "F.Mask" "F.Paste")
			(net "GND")
		)
	)
	(footprint ""
		(layer "F.Cu")
		(at 18.78584 -140.454888)
		(property "Reference" "C393"
			(at -5.1054 0.08382 0)
			(unlocked yes)
			(layer "F.SilkS")
			(effects
				(font
					(size 0.7874 0.5842)
					(thickness 0.1524)
				)
				(justify left)
			)
		)
		(property "Value" ""
			(at 0 0 0)
			(layer "F.Fab")
			(effects
				(font
					(size 1.27 1.27)
				)
			)
		)
		(duplicate_pad_numbers_are_jumpers no)
		(fp_line
			(start -1.905 -0.8636)
			(end 1.905 -0.8636)
			(stroke
				(width 0.1524)
				(type default)
			)
			(layer "F.SilkS")
		)
		(fp_line
			(start -1.905 0.8636)
			(end -1.905 -0.8636)
			(stroke
				(width 0.1524)
				(type default)
			)
			(layer "F.SilkS")
		)
		(fp_line
			(start 0 0.8382)
			(end 0 -0.8382)
			(stroke
				(width 0.1524)
				(type default)
			)
			(layer "F.SilkS")
		)
		(fp_line
			(start 1.905 -0.8636)
			(end 1.905 0.8636)
			(stroke
				(width 0.1524)
				(type default)
			)
			(layer "F.SilkS")
		)
		(fp_line
			(start 1.905 0.8636)
			(end -1.905 0.8636)
			(stroke
				(width 0.1524)
				(type default)
			)
			(layer "F.SilkS")
		)
		(fp_rect
			(start -1.524 0.7366)
			(end 1.524 -0.7366)
			(stroke
				(width 0)
				(type default)
			)
			(fill no)
			(layer "F.CrtYd")
		)
		(pad "1" smd rect
			(at 0.94996 0)
			(size 1.1176 1.3716)
			(layers "F.Cu" "F.Mask" "F.Paste")
			(net "P3V3_NODE1")
		)
		(pad "2" smd rect
			(at -0.94996 0)
			(size 1.1176 1.3716)
			(layers "F.Cu" "F.Mask" "F.Paste")
			(net "GND")
		)
	)
	(footprint ""
		(layer "F.Cu")
		(at 156.828998 -142.93723 -90)
		(property "Reference" "R571"
			(at -1.23063 -0.30607 90)
			(unlocked yes)
			(layer "F.SilkS")
			(effects
				(font
					(size 0.7874 0.5842)
					(thickness 0.1524)
				)
				(justify left)
			)
		)
		(property "Value" ""
			(at 0 0 270)
			(layer "F.Fab")
			(effects
				(font
					(size 1.27 1.27)
				)
			)
		)
		(duplicate_pad_numbers_are_jumpers no)
		(fp_line
			(start -0.7874 0.4064)
			(end -0.7874 -0.4064)
			(stroke
				(width 0.1524)
				(type default)
			)
			(layer "F.SilkS")
		)
		(fp_line
			(start 0.7874 0.4064)
			(end -0.7874 0.4064)
			(stroke
				(width 0.1524)
				(type default)
			)
			(layer "F.SilkS")
		)
		(fp_line
			(start -0.7874 -0.4064)
			(end 0.7874 -0.4064)
			(stroke
				(width 0.1524)
				(type default)
			)
			(layer "F.SilkS")
		)
		(fp_line
			(start 0.7874 -0.4064)
			(end 0.7874 0.4064)
			(stroke
				(width 0.1524)
				(type default)
			)
			(layer "F.SilkS")
		)
		(fp_poly
			(pts
				(xy -0.508 0.2794) (xy -0.508 0.2286) (xy -0.635 0.2286) (xy -0.635 -0.254) (xy -0.5334 -0.254)
				(xy -0.5334 -0.2794) (xy 0.5334 -0.2794) (xy 0.5334 -0.254) (xy 0.635 -0.254) (xy 0.635 0.254) (xy 0.5334 0.254)
				(xy 0.5334 0.2794)
			)
			(stroke
				(width 0)
				(type default)
			)
			(fill no)
			(layer "F.CrtYd")
		)
		(pad "1" smd rect
			(at 0.40005 0 270)
			(size 0.4572 0.508)
			(layers "F.Cu" "F.Mask" "F.Paste")
			(net "P3V3_NODE1")
		)
		(pad "2" smd rect
			(at -0.40005 0 270)
			(size 0.4572 0.508)
			(layers "F.Cu" "F.Mask" "F.Paste")
			(net "LAN2_AUX_PWR")
		)
	)
	(footprint ""
		(layer "F.Cu")
		(at 35.268662 -184.193942)
		(property "Reference" "C777"
			(at -1.557274 -5.586222 0)
			(unlocked yes)
			(layer "F.SilkS")
			(effects
				(font
					(size 0.7874 0.5842)
					(thickness 0.1524)
				)
				(justify left)
			)
		)
		(property "Value" ""
			(at 0 0 0)
			(layer "F.Fab")
			(effects
				(font
					(size 1.27 1.27)
				)
			)
		)
		(duplicate_pad_numbers_are_jumpers no)
		(fp_line
			(start -0.7874 -0.4064)
			(end 0.7874 -0.4064)
			(stroke
				(width 0.1524)
				(type default)
			)
			(layer "F.SilkS")
		)
		(fp_line
			(start -0.7874 0.4064)
			(end -0.7874 -0.4064)
			(stroke
				(width 0.1524)
				(type default)
			)
			(layer "F.SilkS")
		)
		(fp_line
			(start 0 0.381)
			(end 0 -0.381)
			(stroke
				(width 0.1524)
				(type default)
			)
			(layer "F.SilkS")
		)
		(fp_line
			(start 0.7874 -0.4064)
			(end 0.7874 0.4064)
			(stroke
				(width 0.1524)
				(type default)
			)
			(layer "F.SilkS")
		)
		(fp_line
			(start 0.7874 0.4064)
			(end -0.7874 0.4064)
			(stroke
				(width 0.1524)
				(type default)
			)
			(layer "F.SilkS")
		)
		(fp_poly
			(pts
				(xy -0.5334 0.254) (xy -0.635 0.254) (xy -0.635 0.2286) (xy -0.635 -0.254) (xy -0.5334 -0.254) (xy -0.5334 -0.2794)
				(xy 0.5334 -0.2794) (xy 0.5334 -0.254) (xy 0.635 -0.254) (xy 0.635 0.254) (xy 0.5334 0.254) (xy 0.5334 0.2794)
				(xy -0.508 0.2794) (xy -0.5334 0.2794)
			)
			(stroke
				(width 0)
				(type default)
			)
			(fill no)
			(layer "F.CrtYd")
		)
		(pad "1" smd rect
			(at 0.40005 0)
			(size 0.4572 0.508)
			(layers "F.Cu" "F.Mask" "F.Paste")
			(net "P12V_PDB")
		)
		(pad "2" smd rect
			(at -0.40005 0)
			(size 0.4572 0.508)
			(layers "F.Cu" "F.Mask" "F.Paste")
			(net "GND")
		)
	)
	(footprint ""
		(layer "F.Cu")
		(at 133.08076 -185.205624 90)
		(property "Reference" "C749"
			(at 4.510786 -0.278638 90)
			(unlocked yes)
			(layer "F.SilkS")
			(effects
				(font
					(size 0.7874 0.5842)
					(thickness 0.1524)
				)
				(justify left)
			)
		)
		(property "Value" ""
			(at 0 0 90)
			(layer "F.Fab")
			(effects
				(font
					(size 1.27 1.27)
				)
			)
		)
		(duplicate_pad_numbers_are_jumpers no)
		(fp_line
			(start 0.7874 -0.4064)
			(end 0.7874 0.4064)
			(stroke
				(width 0.1524)
				(type default)
			)
			(layer "F.SilkS")
		)
		(fp_line
			(start -0.7874 -0.4064)
			(end 0.7874 -0.4064)
			(stroke
				(width 0.1524)
				(type default)
			)
			(layer "F.SilkS")
		)
		(fp_line
			(start 0 0.381)
			(end 0 -0.381)
			(stroke
				(width 0.1524)
				(type default)
			)
			(layer "F.SilkS")
		)
		(fp_line
			(start 0.7874 0.4064)
			(end -0.7874 0.4064)
			(stroke
				(width 0.1524)
				(type default)
			)
			(layer "F.SilkS")
		)
		(fp_line
			(start -0.7874 0.4064)
			(end -0.7874 -0.4064)
			(stroke
				(width 0.1524)
				(type default)
			)
			(layer "F.SilkS")
		)
		(fp_poly
			(pts
				(xy -0.5334 0.254) (xy -0.635 0.254) (xy -0.635 0.2286) (xy -0.635 -0.254) (xy -0.5334 -0.254) (xy -0.5334 -0.2794)
				(xy 0.5334 -0.2794) (xy 0.5334 -0.254) (xy 0.635 -0.254) (xy 0.635 0.254) (xy 0.5334 0.254) (xy 0.5334 0.2794)
				(xy -0.508 0.2794) (xy -0.5334 0.2794)
			)
			(stroke
				(width 0)
				(type default)
			)
			(fill no)
			(layer "F.CrtYd")
		)
		(pad "1" smd rect
			(at 0.40005 0 90)
			(size 0.4572 0.508)
			(layers "F.Cu" "F.Mask" "F.Paste")
			(net "UART_T10_NODE2_RXD")
		)
		(pad "2" smd rect
			(at -0.40005 0 90)
			(size 0.4572 0.508)
			(layers "F.Cu" "F.Mask" "F.Paste")
			(net "GND")
		)
	)
	(footprint ""
		(layer "F.Cu")
		(at 143.345916 -72.314308 -90)
		(property "Reference" "R513"
			(at 1.013714 -1.270254 90)
			(unlocked yes)
			(layer "F.SilkS")
			(effects
				(font
					(size 0.7874 0.5842)
					(thickness 0.1524)
				)
				(justify left)
			)
		)
		(property "Value" ""
			(at 0 0 270)
			(layer "F.Fab")
			(effects
				(font
					(size 1.27 1.27)
				)
			)
		)
		(duplicate_pad_numbers_are_jumpers no)
		(fp_line
			(start -0.7874 0.4064)
			(end -0.7874 -0.4064)
			(stroke
				(width 0.1524)
				(type default)
			)
			(layer "F.SilkS")
		)
		(fp_line
			(start 0.7874 0.4064)
			(end -0.7874 0.4064)
			(stroke
				(width 0.1524)
				(type default)
			)
			(layer "F.SilkS")
		)
		(fp_line
			(start -0.7874 -0.4064)
			(end 0.7874 -0.4064)
			(stroke
				(width 0.1524)
				(type default)
			)
			(layer "F.SilkS")
		)
		(fp_line
			(start 0.7874 -0.4064)
			(end 0.7874 0.4064)
			(stroke
				(width 0.1524)
				(type default)
			)
			(layer "F.SilkS")
		)
		(fp_poly
			(pts
				(xy -0.508 0.2794) (xy -0.508 0.2286) (xy -0.635 0.2286) (xy -0.635 -0.254) (xy -0.5334 -0.254)
				(xy -0.5334 -0.2794) (xy 0.5334 -0.2794) (xy 0.5334 -0.254) (xy 0.635 -0.254) (xy 0.635 0.254) (xy 0.5334 0.254)
				(xy 0.5334 0.2794)
			)
			(stroke
				(width 0)
				(type default)
			)
			(fill no)
			(layer "F.CrtYd")
		)
		(pad "1" smd rect
			(at 0.40005 0 270)
			(size 0.4572 0.508)
			(layers "F.Cu" "F.Mask" "F.Paste")
			(net "IRQ_LVC3_SATA_NODE1_WAKE_L")
		)
		(pad "2" smd rect
			(at -0.40005 0 270)
			(size 0.4572 0.508)
			(layers "F.Cu" "F.Mask" "F.Paste")
			(net "IRQ_LVC3_CPU_NODE1_WAKE_L")
		)
	)
	(footprint ""
		(layer "F.Cu")
		(at 114.621818 -136.67359)
		(property "Reference" "PC110"
			(at 3.165602 -4.479798 0)
			(unlocked yes)
			(layer "F.SilkS")
			(effects
				(font
					(size 0.635 0.4064)
					(thickness 0.1524)
				)
				(justify left)
			)
		)
		(property "Value" ""
			(at 0 0 0)
			(layer "F.Fab")
			(effects
				(font
					(size 1.27 1.27)
				)
			)
		)
		(duplicate_pad_numbers_are_jumpers no)
		(fp_line
			(start -0.7874 -0.4064)
			(end 0.7874 -0.4064)
			(stroke
				(width 0.1524)
				(type default)
			)
			(layer "F.SilkS")
		)
		(fp_line
			(start -0.7874 0.4064)
			(end -0.7874 -0.4064)
			(stroke
				(width 0.1524)
				(type default)
			)
			(layer "F.SilkS")
		)
		(fp_line
			(start 0 0.381)
			(end 0 -0.381)
			(stroke
				(width 0.1524)
				(type default)
			)
			(layer "F.SilkS")
		)
		(fp_line
			(start 0.7874 -0.4064)
			(end 0.7874 0.4064)
			(stroke
				(width 0.1524)
				(type default)
			)
			(layer "F.SilkS")
		)
		(fp_line
			(start 0.7874 0.4064)
			(end -0.7874 0.4064)
			(stroke
				(width 0.1524)
				(type default)
			)
			(layer "F.SilkS")
		)
		(fp_poly
			(pts
				(xy -0.5334 0.254) (xy -0.635 0.254) (xy -0.635 0.2286) (xy -0.635 -0.254) (xy -0.5334 -0.254) (xy -0.5334 -0.2794)
				(xy 0.5334 -0.2794) (xy 0.5334 -0.254) (xy 0.635 -0.254) (xy 0.635 0.254) (xy 0.5334 0.254) (xy 0.5334 0.2794)
				(xy -0.508 0.2794) (xy -0.5334 0.2794)
			)
			(stroke
				(width 0)
				(type default)
			)
			(fill no)
			(layer "F.CrtYd")
		)
		(pad "1" smd rect
			(at 0.40005 0)
			(size 0.4572 0.508)
			(layers "F.Cu" "F.Mask" "F.Paste")
			(net "AGND_PVCCP_NODE1")
		)
		(pad "2" smd rect
			(at -0.40005 0)
			(size 0.4572 0.508)
			(layers "F.Cu" "F.Mask" "F.Paste")
			(net "VR_PVCCP_NODE1_FB")
		)
	)
	(footprint ""
		(layer "F.Cu")
		(at 80.907128 -140.255752)
		(property "Reference" "C839"
			(at -2.426208 3.661918 0)
			(unlocked yes)
			(layer "F.SilkS")
			(effects
				(font
					(size 0.635 0.4064)
					(thickness 0.1524)
				)
				(justify left)
			)
		)
		(property "Value" ""
			(at 0 0 0)
			(layer "F.Fab")
			(effects
				(font
					(size 1.27 1.27)
				)
			)
		)
		(duplicate_pad_numbers_are_jumpers no)
		(fp_line
			(start -0.7874 -0.4064)
			(end 0.7874 -0.4064)
			(stroke
				(width 0.1524)
				(type default)
			)
			(layer "F.SilkS")
		)
		(fp_line
			(start -0.7874 0.4064)
			(end -0.7874 -0.4064)
			(stroke
				(width 0.1524)
				(type default)
			)
			(layer "F.SilkS")
		)
		(fp_line
			(start 0 0.381)
			(end 0 -0.381)
			(stroke
				(width 0.1524)
				(type default)
			)
			(layer "F.SilkS")
		)
		(fp_line
			(start 0.7874 -0.4064)
			(end 0.7874 0.4064)
			(stroke
				(width 0.1524)
				(type default)
			)
			(layer "F.SilkS")
		)
		(fp_line
			(start 0.7874 0.4064)
			(end -0.7874 0.4064)
			(stroke
				(width 0.1524)
				(type default)
			)
			(layer "F.SilkS")
		)
		(fp_poly
			(pts
				(xy -0.5334 0.254) (xy -0.635 0.254) (xy -0.635 0.2286) (xy -0.635 -0.254) (xy -0.5334 -0.254) (xy -0.5334 -0.2794)
				(xy 0.5334 -0.2794) (xy 0.5334 -0.254) (xy 0.635 -0.254) (xy 0.635 0.254) (xy 0.5334 0.254) (xy 0.5334 0.2794)
				(xy -0.508 0.2794) (xy -0.5334 0.2794)
			)
			(stroke
				(width 0)
				(type default)
			)
			(fill no)
			(layer "F.CrtYd")
		)
		(pad "1" smd rect
			(at 0.40005 0)
			(size 0.4572 0.508)
			(layers "F.Cu" "F.Mask" "F.Paste")
			(net "P1V26_BMC_NODE1")
		)
		(pad "2" smd rect
			(at -0.40005 0)
			(size 0.4572 0.508)
			(layers "F.Cu" "F.Mask" "F.Paste")
			(net "GND")
		)
	)
	(footprint ""
		(layer "F.Cu")
		(at 125.735588 -180.487828 180)
		(property "Reference" "R722"
			(at -1.39446 0.675132 0)
			(unlocked yes)
			(layer "F.SilkS")
			(effects
				(font
					(size 0.7874 0.5842)
					(thickness 0.1524)
				)
				(justify left)
			)
		)
		(property "Value" ""
			(at 0 0 180)
			(layer "F.Fab")
			(effects
				(font
					(size 1.27 1.27)
				)
			)
		)
		(duplicate_pad_numbers_are_jumpers no)
		(fp_line
			(start 0.7874 0.4064)
			(end -0.7874 0.4064)
			(stroke
				(width 0.1524)
				(type default)
			)
			(layer "F.SilkS")
		)
		(fp_line
			(start 0.7874 -0.4064)
			(end 0.7874 0.4064)
			(stroke
				(width 0.1524)
				(type default)
			)
			(layer "F.SilkS")
		)
		(fp_line
			(start -0.7874 0.4064)
			(end -0.7874 -0.4064)
			(stroke
				(width 0.1524)
				(type default)
			)
			(layer "F.SilkS")
		)
		(fp_line
			(start -0.7874 -0.4064)
			(end 0.7874 -0.4064)
			(stroke
				(width 0.1524)
				(type default)
			)
			(layer "F.SilkS")
		)
		(fp_poly
			(pts
				(xy -0.508 0.2794) (xy -0.508 0.2286) (xy -0.635 0.2286) (xy -0.635 -0.254) (xy -0.5334 -0.254)
				(xy -0.5334 -0.2794) (xy 0.5334 -0.2794) (xy 0.5334 -0.254) (xy 0.635 -0.254) (xy 0.635 0.254) (xy 0.5334 0.254)
				(xy 0.5334 0.2794)
			)
			(stroke
				(width 0)
				(type default)
			)
			(fill no)
			(layer "F.CrtYd")
		)
		(pad "1" smd rect
			(at 0.40005 0 180)
			(size 0.4572 0.508)
			(layers "F.Cu" "F.Mask" "F.Paste")
			(net "T7_NODE3_EN")
		)
		(pad "2" smd rect
			(at -0.40005 0 180)
			(size 0.4572 0.508)
			(layers "F.Cu" "F.Mask" "F.Paste")
			(net "P5V_NODE1")
		)
	)
	(footprint ""
		(layer "F.Cu")
		(at 79.91856 -80.683608 -90)
		(property "Reference" "C70"
			(at 17.592294 -1.189482 90)
			(unlocked yes)
			(layer "F.SilkS")
			(effects
				(font
					(size 0.7874 0.5842)
					(thickness 0.1524)
				)
				(justify left)
			)
		)
		(property "Value" ""
			(at 0 0 270)
			(layer "F.Fab")
			(effects
				(font
					(size 1.27 1.27)
				)
			)
		)
		(duplicate_pad_numbers_are_jumpers no)
		(fp_line
			(start -0.7874 0.4064)
			(end -0.7874 -0.4064)
			(stroke
				(width 0.1524)
				(type default)
			)
			(layer "F.SilkS")
		)
		(fp_line
			(start 0.7874 0.4064)
			(end -0.7874 0.4064)
			(stroke
				(width 0.1524)
				(type default)
			)
			(layer "F.SilkS")
		)
		(fp_line
			(start 0 0.381)
			(end 0 -0.381)
			(stroke
				(width 0.1524)
				(type default)
			)
			(layer "F.SilkS")
		)
		(fp_line
			(start -0.7874 -0.4064)
			(end 0.7874 -0.4064)
			(stroke
				(width 0.1524)
				(type default)
			)
			(layer "F.SilkS")
		)
		(fp_line
			(start 0.7874 -0.4064)
			(end 0.7874 0.4064)
			(stroke
				(width 0.1524)
				(type default)
			)
			(layer "F.SilkS")
		)
		(fp_poly
			(pts
				(xy -0.5334 0.254) (xy -0.635 0.254) (xy -0.635 0.2286) (xy -0.635 -0.254) (xy -0.5334 -0.254) (xy -0.5334 -0.2794)
				(xy 0.5334 -0.2794) (xy 0.5334 -0.254) (xy 0.635 -0.254) (xy 0.635 0.254) (xy 0.5334 0.254) (xy 0.5334 0.2794)
				(xy -0.508 0.2794) (xy -0.5334 0.2794)
			)
			(stroke
				(width 0)
				(type default)
			)
			(fill no)
			(layer "F.CrtYd")
		)
		(pad "1" smd rect
			(at 0.40005 0 270)
			(size 0.4572 0.508)
			(layers "F.Cu" "F.Mask" "F.Paste")
			(net "PV_VCCP_NODE1")
		)
		(pad "2" smd rect
			(at -0.40005 0 270)
			(size 0.4572 0.508)
			(layers "F.Cu" "F.Mask" "F.Paste")
			(net "GND")
		)
	)
)
